# SCM (Grand Teton) — schematic netlist excerpt (pin names and nets, part order shuffled) for the footprints in the layout excerpt that follows; sources: Cadence DE-HDL packaged netlist, KiCad conversion of 12092022_DA0F0TMDCD0_F0T_Management_Board_D_brd_V3_OCP.brd

R648  Q_RES  33.2 1% EMPTY  pkg 0402LF  page 21 : A = EMMC_DT1_R ; B = BMC_EMMC_DT1
C52  Q_CAP  1UF 25V 10% X6S  pkg C0402  page 16 : A = P1V0_STBY_PLAVDD ; B = GND

(kicad_pcb
	(version 20260206)
	(generator "pcbnew")
	(generator_version "10.0")
	(general
		(thickness 1.6)
		(legacy_teardrops no)
	)
	(paper "A4")
	(title_block
		(title "12092022_DA0F0TMDCD0_F0T_Management_Board_D_brd_V3_OCP.brd")
		(comment 1 "Grand Teton / footprints 295-296 of 1440")
	)
	(layers
		(0 "F.Cu" signal "TOP")
		(4 "In1.Cu" signal "GND")
		(6 "In2.Cu" signal "IN1")
		(8 "In3.Cu" signal "GND1")
		(10 "In4.Cu" signal "IN2")
		(12 "In5.Cu" signal "VCC")
		(14 "In6.Cu" signal "VCC1")
		(16 "In7.Cu" signal "IN3")
		(18 "In8.Cu" signal "GND2")
		(20 "In9.Cu" signal "IN4")
		(22 "In10.Cu" signal "GND3")
		(2 "B.Cu" signal "BOTTOM")
		(9 "F.Adhes" user "F.Adhesive")
		(11 "B.Adhes" user "B.Adhesive")
		(13 "F.Paste" user "Package Geometry/Pastemask Top")
		(15 "B.Paste" user "Package Geometry/Pastemask Bottom")
		(5 "F.SilkS" user "Ref Des/Silkscreen Top")
		(7 "B.SilkS" user "Ref Des/Silkscreen Bottom")
		(1 "F.Mask" user "Board Geometry/Soldermask Top")
		(3 "B.Mask" user "Board Geometry/Soldermask Bottom")
		(17 "Dwgs.User" user "User.Drawings")
		(19 "Cmts.User" user "User.Comments")
		(21 "Eco1.User" user "User.Eco1")
		(23 "Eco2.User" user "User.Eco2")
		(25 "Edge.Cuts" user "Board Geometry/Outline")
		(27 "Margin" user)
		(31 "F.CrtYd" user "Package Geometry/Place Bound Top")
		(29 "B.CrtYd" user "Package Geometry/Place Bound Bottom")
		(35 "F.Fab" user "Ref Des/Assembly Top")
		(33 "B.Fab" user "Ref Des/Assembly Bottom")
	)
	(footprint ""
		(layer "F.Cu")
		(at 37.063172 -83.816952 90)
		(property "Reference" "R648"
			(at 0 0 90)
			(layer "F.SilkS")
			(hide yes)
			(effects
				(font
					(size 1.27 1.27)
				)
			)
		)
		(property "Value" ""
			(at 0 0 90)
			(layer "F.Fab")
			(effects
				(font
					(size 1.27 1.27)
				)
			)
		)
		(duplicate_pad_numbers_are_jumpers no)
		(fp_line
			(start 0.7874 -0.4064)
			(end 0.7874 0.4064)
			(stroke
				(width 0.1524)
				(type default)
			)
			(layer "F.SilkS")
		)
		(fp_line
			(start -0.7874 -0.4064)
			(end 0.7874 -0.4064)
			(stroke
				(width 0.1524)
				(type default)
			)
			(layer "F.SilkS")
		)
		(fp_line
			(start 0.7874 0.4064)
			(end -0.7874 0.4064)
			(stroke
				(width 0.1524)
				(type default)
			)
			(layer "F.SilkS")
		)
		(fp_line
			(start -0.7874 0.4064)
			(end -0.7874 -0.4064)
			(stroke
				(width 0.1524)
				(type default)
			)
			(layer "F.SilkS")
		)
		(fp_line
			(start -0.12065 -0.305054)
			(end -0.12065 -0.2794)
			(stroke
				(width 0.1)
				(type default)
			)
			(layer "F.Fab")
		)
		(fp_line
			(start -0.67945 -0.305054)
			(end -0.12065 -0.305054)
			(stroke
				(width 0.1)
				(type default)
			)
			(layer "F.Fab")
		)
		(fp_line
			(start 0.67945 -0.3048)
			(end 0.67945 0.3048)
			(stroke
				(width 0.1)
				(type default)
			)
			(layer "F.Fab")
		)
		(fp_line
			(start 0.12065 -0.3048)
			(end 0.67945 -0.3048)
			(stroke
				(width 0.1)
				(type default)
			)
			(layer "F.Fab")
		)
		(fp_line
			(start 0.12065 -0.2794)
			(end 0.12065 -0.3048)
			(stroke
				(width 0.1)
				(type default)
			)
			(layer "F.Fab")
		)
		(fp_line
			(start -0.12065 -0.2794)
			(end 0.12065 -0.2794)
			(stroke
				(width 0.1)
				(type default)
			)
			(layer "F.Fab")
		)
		(fp_line
			(start 0.120396 0.2794)
			(end -0.12065 0.2794)
			(stroke
				(width 0.1)
				(type default)
			)
			(layer "F.Fab")
		)
		(fp_line
			(start -0.12065 0.2794)
			(end -0.12065 0.3048)
			(stroke
				(width 0.1)
				(type default)
			)
			(layer "F.Fab")
		)
		(fp_line
			(start 0.67945 0.3048)
			(end 0.120396 0.3048)
			(stroke
				(width 0.1)
				(type default)
			)
			(layer "F.Fab")
		)
		(fp_line
			(start 0.120396 0.3048)
			(end 0.120396 0.2794)
			(stroke
				(width 0.1)
				(type default)
			)
			(layer "F.Fab")
		)
		(fp_line
			(start -0.12065 0.3048)
			(end -0.67945 0.3048)
			(stroke
				(width 0.1)
				(type default)
			)
			(layer "F.Fab")
		)
		(fp_line
			(start -0.67945 0.3048)
			(end -0.67945 -0.305054)
			(stroke
				(width 0.1)
				(type default)
			)
			(layer "F.Fab")
		)
		(pad "1" smd circle
			(at -0.40005 0 90)
			(size 0 0)
			(layers "F.Cu" "F.Mask" "F.Paste")
			(net "EMMC_DT1_R")
		)
		(pad "2" smd circle
			(at 0.40005 0 90)
			(size 0 0)
			(layers "F.Cu" "F.Mask" "F.Paste")
			(net "BMC_EMMC_DT1")
		)
	)
	(footprint ""
		(layer "F.Cu")
		(at 69.005196 -37.288216 -90)
		(property "Reference" "C52"
			(at 0 0 270)
			(layer "F.SilkS")
			(hide yes)
			(effects
				(font
					(size 1.27 1.27)
				)
			)
		)
		(property "Value" ""
			(at 0 0 270)
			(layer "F.Fab")
			(effects
				(font
					(size 1.27 1.27)
				)
			)
		)
		(duplicate_pad_numbers_are_jumpers no)
		(fp_line
			(start -0.7874 0.4064)
			(end -0.7874 -0.4064)
			(stroke
				(width 0.1524)
				(type default)
			)
			(layer "F.SilkS")
		)
		(fp_line
			(start 0.7874 0.4064)
			(end -0.7874 0.4064)
			(stroke
				(width 0.1524)
				(type default)
			)
			(layer "F.SilkS")
		)
		(fp_line
			(start -0.7874 -0.4064)
			(end 0.7874 -0.4064)
			(stroke
				(width 0.1524)
				(type default)
			)
			(layer "F.SilkS")
		)
		(fp_line
			(start 0.7874 -0.4064)
			(end 0.7874 0.4064)
			(stroke
				(width 0.1524)
				(type default)
			)
			(layer "F.SilkS")
		)
		(fp_line
			(start -0.67945 0.3048)
			(end -0.67945 -0.305054)
			(stroke
				(width 0.1)
				(type default)
			)
			(layer "F.Fab")
		)
		(fp_line
			(start -0.12065 0.3048)
			(end -0.67945 0.3048)
			(stroke
				(width 0.1)
				(type default)
			)
			(layer "F.Fab")
		)
		(fp_line
			(start 0.120396 0.3048)
			(end 0.120396 0.2794)
			(stroke
				(width 0.1)
				(type default)
			)
			(layer "F.Fab")
		)
		(fp_line
			(start 0.67945 0.3048)
			(end 0.120396 0.3048)
			(stroke
				(width 0.1)
				(type default)
			)
			(layer "F.Fab")
		)
		(fp_line
			(start -0.12065 0.2794)
			(end -0.12065 0.3048)
			(stroke
				(width 0.1)
				(type default)
			)
			(layer "F.Fab")
		)
		(fp_line
			(start 0.120396 0.2794)
			(end -0.12065 0.2794)
			(stroke
				(width 0.1)
				(type default)
			)
			(layer "F.Fab")
		)
		(fp_line
			(start -0.12065 -0.2794)
			(end 0.12065 -0.2794)
			(stroke
				(width 0.1)
				(type default)
			)
			(layer "F.Fab")
		)
		(fp_line
			(start 0.12065 -0.2794)
			(end 0.12065 -0.3048)
			(stroke
				(width 0.1)
				(type default)
			)
			(layer "F.Fab")
		)
		(fp_line
			(start 0.12065 -0.3048)
			(end 0.67945 -0.3048)
			(stroke
				(width 0.1)
				(type default)
			)
			(layer "F.Fab")
		)
		(fp_line
			(start 0.67945 -0.3048)
			(end 0.67945 0.3048)
			(stroke
				(width 0.1)
				(type default)
			)
			(layer "F.Fab")
		)
		(fp_line
			(start -0.67945 -0.305054)
			(end -0.12065 -0.305054)
			(stroke
				(width 0.1)
				(type default)
			)
			(layer "F.Fab")
		)
		(fp_line
			(start -0.12065 -0.305054)
			(end -0.12065 -0.2794)
			(stroke
				(width 0.1)
				(type default)
			)
			(layer "F.Fab")
		)
		(pad "1" smd circle
			(at -0.40005 0 270)
			(size 0 0)
			(layers "F.Cu" "F.Mask" "F.Paste")
			(net "P1V0_STBY_PLAVDD")
		)
		(pad "2" smd circle
			(at 0.40005 0 270)
			(size 0 0)
			(layers "F.Cu" "F.Mask" "F.Paste")
			(net "GND")
		)
	)
)
